(kicad_pcb
	(version 20241229)
	(generator "pcbnew")
	(generator_version "9.0")
	(general
		(thickness 1.61)
		(legacy_teardrops no)
	)
	(paper "A3")
	(title_block
		(title "RDIMM DDR5 Tester")
		(date "2026-05-21")
		(rev "2.2.0")
		(company "Antmicro")
		(comment 9 "footprints 623-627 of 796")
	)
	(layers
		(0 "F.Cu" signal)
		(4 "In1.Cu" power)
		(6 "In2.Cu" mixed)
		(8 "In3.Cu" power)
		(10 "In4.Cu" mixed)
		(12 "In5.Cu" power)
		(14 "In6.Cu" mixed)
		(16 "In7.Cu" power)
		(18 "In8.Cu" power)
		(20 "In9.Cu" mixed)
		(22 "In10.Cu" power)
		(2 "B.Cu" signal)
		(9 "F.Adhes" user "F.Adhesive")
		(11 "B.Adhes" user "B.Adhesive")
		(13 "F.Paste" user)
		(15 "B.Paste" user)
		(5 "F.SilkS" user "F.Silkscreen")
		(7 "B.SilkS" user "B.Silkscreen")
		(1 "F.Mask" user)
		(3 "B.Mask" user)
		(17 "Dwgs.User" user "User.Drawings")
		(19 "Cmts.User" user "User.Comments")
		(21 "Eco1.User" user "User.Eco1")
		(23 "Eco2.User" user "User.Eco2")
		(25 "Edge.Cuts" user)
		(27 "Margin" user)
		(31 "F.CrtYd" user "F.Courtyard")
		(29 "B.CrtYd" user "B.Courtyard")
		(35 "F.Fab" user)
		(33 "B.Fab" user)
	)
	(footprint "antmicro-footprints:C_0402_1005Metric_EIA"
		(layer "B.Cu")
		(at 187 154.499999 -90)
		(descr "Capacitor SMD 0402 (1005 Metric), square (rectangular) end terminal, IPC_7351 nominal, (Body size source: IPC-SM-782 page 76, https://www.pcb-3d.com/wordpress/wp-content/uploads/ipc-sm-782a_amendment_1_and_2.pdf)")
		(tags "capacitor 0402")
		(property "Reference" "C45"
			(at -12.024999 30.625 90)
			(layer "B.SilkS")
			(effects
				(font
					(size 0.7 0.7)
					(thickness 0.15)
				)
				(justify left bottom mirror)
			)
		)
		(property "Value" "C_1u_25V_0402"
			(at 0 -1.169 90)
			(layer "B.Fab")
			(effects
				(font
					(size 0.7 0.7)
					(thickness 0.15)
				)
				(justify left bottom mirror)
			)
		)
		(property "Datasheet" "https://www.murata.com/products/productdetail?partno=GRM155R61E105KE11%23"
			(at 0 0 270)
			(layer "F.Fab")
			(hide yes)
			(effects
				(font
					(size 1.27 1.27)
					(thickness 0.15)
				)
			)
		)
		(property "MPN" "GRM155R61E105KE11J"
			(at 0 0 270)
			(unlocked yes)
			(layer "B.Fab")
			(hide yes)
			(effects
				(font
					(size 1 1)
					(thickness 0.15)
				)
				(justify mirror)
			)
		)
		(property "Manufacturer" "Murata"
			(at 0 0 270)
			(unlocked yes)
			(layer "B.Fab")
			(hide yes)
			(effects
				(font
					(size 1 1)
					(thickness 0.15)
				)
				(justify mirror)
			)
		)
		(property "License" "Apache-2.0"
			(at 0 0 270)
			(unlocked yes)
			(layer "B.Fab")
			(hide yes)
			(effects
				(font
					(size 1 1)
					(thickness 0.15)
				)
				(justify mirror)
			)
		)
		(property "Author" "Antmicro"
			(at 0 0 270)
			(unlocked yes)
			(layer "B.Fab")
			(hide yes)
			(effects
				(font
					(size 1 1)
					(thickness 0.15)
				)
				(justify mirror)
			)
		)
		(property "Val" "1u"
			(at 0 0 270)
			(unlocked yes)
			(layer "B.Fab")
			(hide yes)
			(effects
				(font
					(size 1 1)
					(thickness 0.15)
				)
				(justify mirror)
			)
		)
		(property "Voltage" "25V"
			(at 0 0 270)
			(unlocked yes)
			(layer "B.Fab")
			(hide yes)
			(effects
				(font
					(size 1 1)
					(thickness 0.15)
				)
				(justify mirror)
			)
		)
		(property "Dielectric" "X5R"
			(at 0 0 270)
			(unlocked yes)
			(layer "B.Fab")
			(hide yes)
			(effects
				(font
					(size 1 1)
					(thickness 0.15)
				)
				(justify mirror)
			)
		)
		(sheetname "/FPGA power/")
		(sheetfile "fpga-power.kicad_sch")
		(attr smd)
		(fp_rect
			(start -0.95 0.45)
			(end 0.95 -0.45)
			(stroke
				(width 0.05)
				(type default)
			)
			(fill no)
			(layer "B.CrtYd")
		)
		(fp_line
			(start -0.5 0.25)
			(end 0.498 0.25)
			(stroke
				(width 0.15)
				(type solid)
			)
			(layer "B.Fab")
		)
		(fp_line
			(start 0.498 0.25)
			(end 0.498 -0.248)
			(stroke
				(width 0.15)
				(type solid)
			)
			(layer "B.Fab")
		)
		(fp_line
			(start -0.5 -0.248)
			(end -0.5 0.25)
			(stroke
				(width 0.15)
				(type solid)
			)
			(layer "B.Fab")
		)
		(fp_line
			(start 0.498 -0.248)
			(end -0.5 -0.248)
			(stroke
				(width 0.15)
				(type solid)
			)
			(layer "B.Fab")
		)
		(fp_text user "Author: Antmicro"
			(at -0.9656 -5.569 90)
			(layer "B.Fab")
			(effects
				(font
					(size 0.7 0.7)
					(thickness 0.15)
				)
				(justify left bottom mirror)
			)
		)
		(fp_text user "License: Apache-2.0"
			(at -0.9656 -4.369 90)
			(layer "B.Fab")
			(effects
				(font
					(size 0.7 0.7)
					(thickness 0.15)
				)
				(justify left bottom mirror)
			)
		)
		(fp_text user "${REFERENCE}"
			(at -0.9656 -3.169 90)
			(layer "B.Fab")
			(effects
				(font
					(size 0.7 0.7)
					(thickness 0.15)
				)
				(justify left bottom mirror)
			)
		)
		(pad "1" smd roundrect
			(at -0.5 0 180)
			(size 0.6 0.6)
			(layers "B.Cu" "B.Mask" "B.Paste")
			(roundrect_rratio 0.25)
			(net 1 "GND")
			(pintype "passive")
		)
		(pad "2" smd roundrect
			(at 0.498 0 270)
			(size 0.6 0.6)
			(layers "B.Cu" "B.Mask" "B.Paste")
			(roundrect_rratio 0.25)
			(net 553 "+0V85")
			(pintype "passive")
		)
	)
	(footprint "antmicro-footprints:C_0402_1005Metric"
		(layer "B.Cu")
		(at 260.574499 173.799 -90)
		(descr "Capacitor SMD 0402")
		(tags "capacitor SMD 0402")
		(property "Reference" "C172"
			(at -1.799 -1.575501 90)
			(layer "B.SilkS")
			(effects
				(font
					(size 0.7 0.7)
					(thickness 0.15)
				)
				(justify left bottom mirror)
			)
		)
		(property "Value" "C_1u_0402"
			(at -1.022927 -2.155213 90)
			(layer "B.Fab")
			(effects
				(font
					(size 0.7 0.7)
					(thickness 0.15)
				)
				(justify left bottom mirror)
			)
		)
		(property "Datasheet" "https://product.tdk.com/en/search/capacitor/ceramic/mlcc/info?part_no=C1005X6S1A105K050BC"
			(at 0 0 270)
			(layer "F.Fab")
			(hide yes)
			(effects
				(font
					(size 1.27 1.27)
					(thickness 0.15)
				)
			)
		)
		(property "Manufacturer" "TDK"
			(at 0 0 270)
			(unlocked yes)
			(layer "B.Fab")
			(hide yes)
			(effects
				(font
					(size 1 1)
					(thickness 0.15)
				)
				(justify mirror)
			)
		)
		(property "MPN" "C1005X6S1A105K050BC"
			(at 0 0 270)
			(unlocked yes)
			(layer "B.Fab")
			(hide yes)
			(effects
				(font
					(size 1 1)
					(thickness 0.15)
				)
				(justify mirror)
			)
		)
		(property "Val" "1u"
			(at 0 0 270)
			(unlocked yes)
			(layer "B.Fab")
			(hide yes)
			(effects
				(font
					(size 1 1)
					(thickness 0.15)
				)
				(justify mirror)
			)
		)
		(property "License" "Apache-2.0"
			(at 0 0 270)
			(unlocked yes)
			(layer "B.Fab")
			(hide yes)
			(effects
				(font
					(size 1 1)
					(thickness 0.15)
				)
				(justify mirror)
			)
		)
		(property "Author" "Antmicro"
			(at 0 0 270)
			(unlocked yes)
			(layer "B.Fab")
			(hide yes)
			(effects
				(font
					(size 1 1)
					(thickness 0.15)
				)
				(justify mirror)
			)
		)
		(property "Voltage" ""
			(at 0 0 270)
			(unlocked yes)
			(layer "B.Fab")
			(hide yes)
			(effects
				(font
					(size 1 1)
					(thickness 0.15)
				)
				(justify mirror)
			)
		)
		(property "Dielectric" ""
			(at 0 0 270)
			(unlocked yes)
			(layer "B.Fab")
			(hide yes)
			(effects
				(font
					(size 1 1)
					(thickness 0.15)
				)
				(justify mirror)
			)
		)
		(sheetname "/Supply/DC-DC AUX, MGT/")
		(sheetfile "dc-dc-aux-mgt.kicad_sch")
		(attr smd)
		(fp_rect
			(start -0.925 0.47)
			(end 0.925 -0.47)
			(stroke
				(width 0.05)
				(type default)
			)
			(fill no)
			(layer "B.CrtYd")
		)
		(fp_line
			(start -0.494 0.25)
			(end 0.504 0.25)
			(stroke
				(width 0.15)
				(type solid)
			)
			(layer "B.Fab")
		)
		(fp_line
			(start 0.504 0.25)
			(end 0.504 -0.248)
			(stroke
				(width 0.15)
				(type solid)
			)
			(layer "B.Fab")
		)
		(fp_line
			(start -0.494 -0.248)
			(end -0.494 0.25)
			(stroke
				(width 0.15)
				(type solid)
			)
			(layer "B.Fab")
		)
		(fp_line
			(start 0.504 -0.248)
			(end -0.494 -0.248)
			(stroke
				(width 0.15)
				(type solid)
			)
			(layer "B.Fab")
		)
		(fp_text user "License: Apache-2.0"
			(at -0.939 -5.799 90)
			(layer "B.Fab")
			(effects
				(font
					(size 0.7 0.7)
					(thickness 0.15)
				)
				(justify left bottom mirror)
			)
		)
		(fp_text user "${REFERENCE}"
			(at -0.939 -4.599 90)
			(layer "B.Fab")
			(effects
				(font
					(size 0.7 0.7)
					(thickness 0.15)
				)
				(justify left bottom mirror)
			)
		)
		(fp_text user "Author: Antmicro"
			(at -0.939 -3.399 90)
			(layer "B.Fab")
			(effects
				(font
					(size 0.7 0.7)
					(thickness 0.15)
				)
				(justify left bottom mirror)
			)
		)
		(pad "1" smd roundrect
			(at -0.48 0 270)
			(size 0.59 0.64)
			(layers "B.Cu" "B.Mask" "B.Paste")
			(roundrect_rratio 0.25)
			(net 1 "GND")
			(pintype "passive")
		)
		(pad "2" smd roundrect
			(at 0.48 0 270)
			(size 0.59 0.64)
			(layers "B.Cu" "B.Mask" "B.Paste")
			(roundrect_rratio 0.25)
			(net 9 "/Supply/DC-DC AUX, MGT/QDCDC1_VCC")
			(pintype "passive")
		)
	)
	(footprint "antmicro-footprints:C_0402_1005Metric"
		(layer "B.Cu")
		(at 171.65 193.299501 90)
		(descr "Capacitor SMD 0402")
		(tags "capacitor SMD 0402")
		(property "Reference" "C227"
			(at 0.994 0.403501 90)
			(layer "B.SilkS")
			(effects
				(font
					(size 0.7 0.7)
					(thickness 0.15)
				)
				(justify right bottom mirror)
			)
		)
		(property "Value" "C_100n_0402"
			(at -1.022927 -2.155213 90)
			(layer "B.Fab")
			(effects
				(font
					(size 0.7 0.7)
					(thickness 0.15)
				)
				(justify right bottom mirror)
			)
		)
		(property "Datasheet" "https://www.murata.com/products/productdetail?partno=GRM155R61H104KE14%23"
			(at 0 0 90)
			(layer "F.Fab")
			(hide yes)
			(effects
				(font
					(size 1.27 1.27)
					(thickness 0.15)
				)
			)
		)
		(property "Manufacturer" "Murata"
			(at 0 0 90)
			(unlocked yes)
			(layer "B.Fab")
			(hide yes)
			(effects
				(font
					(size 1 1)
					(thickness 0.15)
				)
				(justify mirror)
			)
		)
		(property "MPN" "GRM155R61H104KE14D"
			(at 0 0 90)
			(unlocked yes)
			(layer "B.Fab")
			(hide yes)
			(effects
				(font
					(size 1 1)
					(thickness 0.15)
				)
				(justify mirror)
			)
		)
		(property "Val" "100n"
			(at 0 0 90)
			(unlocked yes)
			(layer "B.Fab")
			(hide yes)
			(effects
				(font
					(size 1 1)
					(thickness 0.15)
				)
				(justify mirror)
			)
		)
		(property "License" "Apache-2.0"
			(at 0 0 90)
			(unlocked yes)
			(layer "B.Fab")
			(hide yes)
			(effects
				(font
					(size 1 1)
					(thickness 0.15)
				)
				(justify mirror)
			)
		)
		(property "Author" "Antmicro"
			(at 0 0 90)
			(unlocked yes)
			(layer "B.Fab")
			(hide yes)
			(effects
				(font
					(size 1 1)
					(thickness 0.15)
				)
				(justify mirror)
			)
		)
		(property "Voltage" "50V"
			(at 0 0 90)
			(unlocked yes)
			(layer "B.Fab")
			(hide yes)
			(effects
				(font
					(size 1 1)
					(thickness 0.15)
				)
				(justify mirror)
			)
		)
		(property "Dielectric" "X5R"
			(at 0 0 90)
			(unlocked yes)
			(layer "B.Fab")
			(hide yes)
			(effects
				(font
					(size 1 1)
					(thickness 0.15)
				)
				(justify mirror)
			)
		)
		(sheetname "/FPGA MGT Interface/")
		(sheetfile "fpga-mgt.kicad_sch")
		(attr smd)
		(fp_rect
			(start -0.925 0.47)
			(end 0.925 -0.47)
			(stroke
				(width 0.05)
				(type default)
			)
			(fill no)
			(layer "B.CrtYd")
		)
		(fp_line
			(start 0.504 -0.248)
			(end -0.494 -0.248)
			(stroke
				(width 0.15)
				(type solid)
			)
			(layer "B.Fab")
		)
		(fp_line
			(start -0.494 -0.248)
			(end -0.494 0.25)
			(stroke
				(width 0.15)
				(type solid)
			)
			(layer "B.Fab")
		)
		(fp_line
			(start 0.504 0.25)
			(end 0.504 -0.248)
			(stroke
				(width 0.15)
				(type solid)
			)
			(layer "B.Fab")
		)
		(fp_line
			(start -0.494 0.25)
			(end 0.504 0.25)
			(stroke
				(width 0.15)
				(type solid)
			)
			(layer "B.Fab")
		)
		(fp_text user "Author: Antmicro"
			(at -0.939 -3.399 270)
			(layer "B.Fab")
			(effects
				(font
					(size 0.7 0.7)
					(thickness 0.15)
				)
				(justify left bottom mirror)
			)
		)
		(fp_text user "License: Apache-2.0"
			(at -0.939 -5.799 270)
			(layer "B.Fab")
			(effects
				(font
					(size 0.7 0.7)
					(thickness 0.15)
				)
				(justify left bottom mirror)
			)
		)
		(fp_text user "${REFERENCE}"
			(at -0.939 -4.599 270)
			(layer "B.Fab")
			(effects
				(font
					(size 0.7 0.7)
					(thickness 0.15)
				)
				(justify left bottom mirror)
			)
		)
		(pad "1" smd roundrect
			(at -0.48 0 90)
			(size 0.59 0.64)
			(layers "B.Cu" "B.Mask" "B.Paste")
			(roundrect_rratio 0.25)
			(net 17 "/FPGA MGT Interface/PCIE.TXD2_P")
			(pintype "passive")
		)
		(pad "2" smd roundrect
			(at 0.48 0 90)
			(size 0.59 0.64)
			(layers "B.Cu" "B.Mask" "B.Paste")
			(roundrect_rratio 0.25)
			(net 18 "/FPGA MGT Interface/GTY_225_TX1_P")
			(pintype "passive")
		)
	)
	(footprint "antmicro-footprints:R_0402_1005Metric"
		(layer "B.Cu")
		(at 117.12 140.5 180)
		(descr "Resistor SMD 0402")
		(tags "resistor SMD 0402")
		(property "Reference" "R251"
			(at -1.28 0.6 0)
			(layer "B.SilkS")
			(effects
				(font
					(size 0.7 0.7)
					(thickness 0.15)
				)
				(justify left bottom mirror)
			)
		)
		(property "Value" "R_0R_0402"
			(at -1.011843 -1.772047 0)
			(layer "B.Fab")
			(effects
				(font
					(size 0.7 0.7)
					(thickness 0.15)
				)
				(justify left bottom mirror)
			)
		)
		(property "Datasheet" "https://industrial.panasonic.com/cdbs/www-data/pdf/RDA0000/AOA0000C301.pdf"
			(at 0 0 0)
			(layer "B.Fab")
			(hide yes)
			(effects
				(font
					(size 1.27 1.27)
					(thickness 0.15)
				)
				(justify mirror)
			)
		)
		(property "Description" "SMD Chip Resistor, Jumper, 0 ohm, 100 mW, 0402 [1005 Metric], Thick Film, General Purpose"
			(at 0 0 0)
			(layer "B.Fab")
			(hide yes)
			(effects
				(font
					(size 1.27 1.27)
					(thickness 0.15)
				)
				(justify mirror)
			)
		)
		(property "MPN" "ERJ2GE0R00X"
			(at 0 0 180)
			(unlocked yes)
			(layer "B.Fab")
			(hide yes)
			(effects
				(font
					(size 1 1)
					(thickness 0.15)
				)
				(justify mirror)
			)
		)
		(property "Manufacturer" "Panasonic"
			(at 0 0 180)
			(unlocked yes)
			(layer "B.Fab")
			(hide yes)
			(effects
				(font
					(size 1 1)
					(thickness 0.15)
				)
				(justify mirror)
			)
		)
		(property "License" "Apache-2.0"
			(at 0 0 180)
			(unlocked yes)
			(layer "B.Fab")
			(hide yes)
			(effects
				(font
					(size 1 1)
					(thickness 0.15)
				)
				(justify mirror)
			)
		)
		(property "Author" "Antmicro"
			(at 0 0 180)
			(unlocked yes)
			(layer "B.Fab")
			(hide yes)
			(effects
				(font
					(size 1 1)
					(thickness 0.15)
				)
				(justify mirror)
			)
		)
		(property "Val" "0R"
			(at 0 0 180)
			(unlocked yes)
			(layer "B.Fab")
			(hide yes)
			(effects
				(font
					(size 1 1)
					(thickness 0.15)
				)
				(justify mirror)
			)
		)
		(property "Tolerance" "~"
			(at 0 0 180)
			(unlocked yes)
			(layer "B.Fab")
			(hide yes)
			(effects
				(font
					(size 1 1)
					(thickness 0.15)
				)
				(justify mirror)
			)
		)
		(property "Current" "1A"
			(at 0 0 180)
			(unlocked yes)
			(layer "B.Fab")
			(hide yes)
			(effects
				(font
					(size 1 1)
					(thickness 0.15)
				)
				(justify mirror)
			)
		)
		(sheetname "/Debug FTDI + VNA/")
		(sheetfile "debug-ftdi.kicad_sch")
		(attr smd exclude_from_bom dnp)
		(fp_rect
			(start -0.925 0.47)
			(end 0.925 -0.47)
			(stroke
				(width 0.05)
				(type default)
			)
			(fill no)
			(layer "B.CrtYd")
		)
		(fp_rect
			(start -0.5 0.25)
			(end 0.5 -0.25)
			(stroke
				(width 0.15)
				(type solid)
			)
			(fill no)
			(layer "B.Fab")
		)
		(fp_text user "Author: Antmicro"
			(at -0.95 -4.169 0)
			(layer "B.Fab")
			(effects
				(font
					(size 0.7 0.7)
					(thickness 0.15)
				)
				(justify left bottom mirror)
			)
		)
		(fp_text user "${REFERENCE}"
			(at -0.95 -3.168 0)
			(layer "B.Fab")
			(effects
				(font
					(size 0.7 0.7)
					(thickness 0.15)
				)
				(justify left bottom mirror)
			)
		)
		(fp_text user "License: Apache-2.0"
			(at -0.95 -5.169 0)
			(layer "B.Fab")
			(effects
				(font
					(size 0.7 0.7)
					(thickness 0.15)
				)
				(justify left bottom mirror)
			)
		)
		(pad "1" smd roundrect
			(at -0.48 0 180)
			(size 0.59 0.64)
			(layers "B.Cu" "B.Mask" "B.Paste")
			(roundrect_rratio 0.25)
			(net 818 "Net-(D17-A)")
			(pintype "passive")
		)
		(pad "2" smd roundrect
			(at 0.48 0 180)
			(size 0.59 0.64)
			(layers "B.Cu" "B.Mask" "B.Paste")
			(roundrect_rratio 0.25)
			(net 6 "/Debug FTDI + VNA/FTDI_3V3")
			(pintype "passive")
		)
	)
	(footprint "antmicro-footprints:C_0402_1005Metric_EIA"
		(layer "B.Cu")
		(at 193 158.5 90)
		(descr "Capacitor SMD 0402 (1005 Metric), square (rectangular) end terminal, IPC_7351 nominal, (Body size source: IPC-SM-782 page 76, https://www.pcb-3d.com/wordpress/wp-content/uploads/ipc-sm-782a_amendment_1_and_2.pdf)")
		(tags "capacitor 0402")
		(property "Reference" "C55"
			(at 9.525 -30.65 90)
			(layer "B.SilkS")
			(effects
				(font
					(size 0.7 0.7)
					(thickness 0.15)
				)
				(justify right bottom mirror)
			)
		)
		(property "Value" "C_100n_0402"
			(at 0 -1.169 90)
			(layer "B.Fab")
			(effects
				(font
					(size 0.7 0.7)
					(thickness 0.15)
				)
				(justify right bottom mirror)
			)
		)
		(property "Datasheet" "https://www.murata.com/products/productdetail?partno=GRM155R61H104KE14%23"
			(at 0 0 90)
			(layer "F.Fab")
			(hide yes)
			(effects
				(font
					(size 1.27 1.27)
					(thickness 0.15)
				)
			)
		)
		(property "MPN" "GRM155R61H104KE14D"
			(at 0 0 90)
			(unlocked yes)
			(layer "B.Fab")
			(hide yes)
			(effects
				(font
					(size 1 1)
					(thickness 0.15)
				)
				(justify mirror)
			)
		)
		(property "Manufacturer" "Murata"
			(at 0 0 90)
			(unlocked yes)
			(layer "B.Fab")
			(hide yes)
			(effects
				(font
					(size 1 1)
					(thickness 0.15)
				)
				(justify mirror)
			)
		)
		(property "License" "Apache-2.0"
			(at 0 0 90)
			(unlocked yes)
			(layer "B.Fab")
			(hide yes)
			(effects
				(font
					(size 1 1)
					(thickness 0.15)
				)
				(justify mirror)
			)
		)
		(property "Author" "Antmicro"
			(at 0 0 90)
			(unlocked yes)
			(layer "B.Fab")
			(hide yes)
			(effects
				(font
					(size 1 1)
					(thickness 0.15)
				)
				(justify mirror)
			)
		)
		(property "Val" "100n"
			(at 0 0 90)
			(unlocked yes)
			(layer "B.Fab")
			(hide yes)
			(effects
				(font
					(size 1 1)
					(thickness 0.15)
				)
				(justify mirror)
			)
		)
		(property "Voltage" "50V"
			(at 0 0 90)
			(unlocked yes)
			(layer "B.Fab")
			(hide yes)
			(effects
				(font
					(size 1 1)
					(thickness 0.15)
				)
				(justify mirror)
			)
		)
		(property "Dielectric" "X5R"
			(at 0 0 90)
			(unlocked yes)
			(layer "B.Fab")
			(hide yes)
			(effects
				(font
					(size 1 1)
					(thickness 0.15)
				)
				(justify mirror)
			)
		)
		(sheetname "/FPGA power/")
		(sheetfile "fpga-power.kicad_sch")
		(attr smd)
		(fp_rect
			(start -0.95 0.45)
			(end 0.95 -0.45)
			(stroke
				(width 0.05)
				(type default)
			)
			(fill no)
			(layer "B.CrtYd")
		)
		(fp_line
			(start 0.498 -0.248)
			(end -0.5 -0.248)
			(stroke
				(width 0.15)
				(type solid)
			)
			(layer "B.Fab")
		)
		(fp_line
			(start -0.5 -0.248)
			(end -0.5 0.25)
			(stroke
				(width 0.15)
				(type solid)
			)
			(layer "B.Fab")
		)
		(fp_line
			(start 0.498 0.25)
			(end 0.498 -0.248)
			(stroke
				(width 0.15)
				(type solid)
			)
			(layer "B.Fab")
		)
		(fp_line
			(start -0.5 0.25)
			(end 0.498 0.25)
			(stroke
				(width 0.15)
				(type solid)
			)
			(layer "B.Fab")
		)
		(fp_text user "License: Apache-2.0"
			(at -0.9656 -4.369 270)
			(layer "B.Fab")
			(effects
				(font
					(size 0.7 0.7)
					(thickness 0.15)
				)
				(justify left bottom mirror)
			)
		)
		(fp_text user "Author: Antmicro"
			(at -0.9656 -5.569 270)
			(layer "B.Fab")
			(effects
				(font
					(size 0.7 0.7)
					(thickness 0.15)
				)
				(justify left bottom mirror)
			)
		)
		(fp_text user "${REFERENCE}"
			(at -0.9656 -3.169 270)
			(layer "B.Fab")
			(effects
				(font
					(size 0.7 0.7)
					(thickness 0.15)
				)
				(justify left bottom mirror)
			)
		)
		(pad "1" smd roundrect
			(at -0.5 0)
			(size 0.6 0.6)
			(layers "B.Cu" "B.Mask" "B.Paste")
			(roundrect_rratio 0.25)
			(net 1 "GND")
			(pintype "passive")
		)
		(pad "2" smd roundrect
			(at 0.498 0 90)
			(size 0.6 0.6)
			(layers "B.Cu" "B.Mask" "B.Paste")
			(roundrect_rratio 0.25)
			(net 553 "+0V85")
			(pintype "passive")
		)
	)
)
